(kicad_pcb
	(version 20260206)
	(generator "pcbnew")
	(generator_version "10.0")
	(general
		(thickness 1.6)
		(legacy_teardrops no)
	)
	(paper "A4")
	(title_block
		(title "12092022_DA0F0TMDCD0_F0T_Management_Board_D_brd_V3_OCP.brd")
		(comment 1 "Grand Teton / footprints 61-66 of 1440")
	)
	(layers
		(0 "F.Cu" signal "TOP")
		(4 "In1.Cu" signal "GND")
		(6 "In2.Cu" signal "IN1")
		(8 "In3.Cu" signal "GND1")
		(10 "In4.Cu" signal "IN2")
		(12 "In5.Cu" signal "VCC")
		(14 "In6.Cu" signal "VCC1")
		(16 "In7.Cu" signal "IN3")
		(18 "In8.Cu" signal "GND2")
		(20 "In9.Cu" signal "IN4")
		(22 "In10.Cu" signal "GND3")
		(2 "B.Cu" signal "BOTTOM")
		(9 "F.Adhes" user "F.Adhesive")
		(11 "B.Adhes" user "B.Adhesive")
		(13 "F.Paste" user "Package Geometry/Pastemask Top")
		(15 "B.Paste" user "Package Geometry/Pastemask Bottom")
		(5 "F.SilkS" user "Ref Des/Silkscreen Top")
		(7 "B.SilkS" user "Ref Des/Silkscreen Bottom")
		(1 "F.Mask" user "Board Geometry/Soldermask Top")
		(3 "B.Mask" user "Board Geometry/Soldermask Bottom")
		(17 "Dwgs.User" user "User.Drawings")
		(19 "Cmts.User" user "User.Comments")
		(21 "Eco1.User" user "User.Eco1")
		(23 "Eco2.User" user "User.Eco2")
		(25 "Edge.Cuts" user "Board Geometry/Outline")
		(27 "Margin" user)
		(31 "F.CrtYd" user "Package Geometry/Place Bound Top")
		(29 "B.CrtYd" user "Package Geometry/Place Bound Bottom")
		(35 "F.Fab" user "Ref Des/Assembly Top")
		(33 "B.Fab" user "Ref Des/Assembly Bottom")
	)
	(footprint ""
		(layer "F.Cu")
		(at 10.739374 -52.008532 90)
		(property "Reference" "PR522"
			(at 0 0 90)
			(layer "F.SilkS")
			(hide yes)
			(effects
				(font
					(size 1.27 1.27)
				)
			)
		)
		(property "Value" ""
			(at 0 0 90)
			(layer "F.Fab")
			(effects
				(font
					(size 1.27 1.27)
				)
			)
		)
		(duplicate_pad_numbers_are_jumpers no)
		(fp_line
			(start 0.7874 -0.4064)
			(end 0.7874 0.4064)
			(stroke
				(width 0.1524)
				(type default)
			)
			(layer "F.SilkS")
		)
		(fp_line
			(start -0.7874 -0.4064)
			(end 0.7874 -0.4064)
			(stroke
				(width 0.1524)
				(type default)
			)
			(layer "F.SilkS")
		)
		(fp_line
			(start 0.7874 0.4064)
			(end -0.7874 0.4064)
			(stroke
				(width 0.1524)
				(type default)
			)
			(layer "F.SilkS")
		)
		(fp_line
			(start -0.7874 0.4064)
			(end -0.7874 -0.4064)
			(stroke
				(width 0.1524)
				(type default)
			)
			(layer "F.SilkS")
		)
		(fp_line
			(start -0.12065 -0.305054)
			(end -0.12065 -0.2794)
			(stroke
				(width 0.1)
				(type default)
			)
			(layer "F.Fab")
		)
		(fp_line
			(start -0.67945 -0.305054)
			(end -0.12065 -0.305054)
			(stroke
				(width 0.1)
				(type default)
			)
			(layer "F.Fab")
		)
		(fp_line
			(start 0.67945 -0.3048)
			(end 0.67945 0.3048)
			(stroke
				(width 0.1)
				(type default)
			)
			(layer "F.Fab")
		)
		(fp_line
			(start 0.12065 -0.3048)
			(end 0.67945 -0.3048)
			(stroke
				(width 0.1)
				(type default)
			)
			(layer "F.Fab")
		)
		(fp_line
			(start 0.12065 -0.2794)
			(end 0.12065 -0.3048)
			(stroke
				(width 0.1)
				(type default)
			)
			(layer "F.Fab")
		)
		(fp_line
			(start -0.12065 -0.2794)
			(end 0.12065 -0.2794)
			(stroke
				(width 0.1)
				(type default)
			)
			(layer "F.Fab")
		)
		(fp_line
			(start 0.120396 0.2794)
			(end -0.12065 0.2794)
			(stroke
				(width 0.1)
				(type default)
			)
			(layer "F.Fab")
		)
		(fp_line
			(start -0.12065 0.2794)
			(end -0.12065 0.3048)
			(stroke
				(width 0.1)
				(type default)
			)
			(layer "F.Fab")
		)
		(fp_line
			(start 0.67945 0.3048)
			(end 0.120396 0.3048)
			(stroke
				(width 0.1)
				(type default)
			)
			(layer "F.Fab")
		)
		(fp_line
			(start 0.120396 0.3048)
			(end 0.120396 0.2794)
			(stroke
				(width 0.1)
				(type default)
			)
			(layer "F.Fab")
		)
		(fp_line
			(start -0.12065 0.3048)
			(end -0.67945 0.3048)
			(stroke
				(width 0.1)
				(type default)
			)
			(layer "F.Fab")
		)
		(fp_line
			(start -0.67945 0.3048)
			(end -0.67945 -0.305054)
			(stroke
				(width 0.1)
				(type default)
			)
			(layer "F.Fab")
		)
		(pad "1" smd circle
			(at -0.40005 0 90)
			(size 0 0)
			(layers "F.Cu" "F.Mask" "F.Paste")
			(net "EN_P5V_AUX")
		)
		(pad "2" smd circle
			(at 0.40005 0 90)
			(size 0 0)
			(layers "F.Cu" "F.Mask" "F.Paste")
			(net "GND")
		)
	)
	(footprint ""
		(layer "F.Cu")
		(at 78.723744 -37.559488 -90)
		(property "Reference" "R361"
			(at 0 0 270)
			(layer "F.SilkS")
			(hide yes)
			(effects
				(font
					(size 1.27 1.27)
				)
			)
		)
		(property "Value" ""
			(at 0 0 270)
			(layer "F.Fab")
			(effects
				(font
					(size 1.27 1.27)
				)
			)
		)
		(duplicate_pad_numbers_are_jumpers no)
		(fp_line
			(start -0.7874 0.4064)
			(end -0.7874 -0.4064)
			(stroke
				(width 0.1524)
				(type default)
			)
			(layer "F.SilkS")
		)
		(fp_line
			(start 0.7874 0.4064)
			(end -0.7874 0.4064)
			(stroke
				(width 0.1524)
				(type default)
			)
			(layer "F.SilkS")
		)
		(fp_line
			(start -0.7874 -0.4064)
			(end 0.7874 -0.4064)
			(stroke
				(width 0.1524)
				(type default)
			)
			(layer "F.SilkS")
		)
		(fp_line
			(start 0.7874 -0.4064)
			(end 0.7874 0.4064)
			(stroke
				(width 0.1524)
				(type default)
			)
			(layer "F.SilkS")
		)
		(fp_line
			(start -0.67945 0.3048)
			(end -0.67945 -0.305054)
			(stroke
				(width 0.1)
				(type default)
			)
			(layer "F.Fab")
		)
		(fp_line
			(start -0.12065 0.3048)
			(end -0.67945 0.3048)
			(stroke
				(width 0.1)
				(type default)
			)
			(layer "F.Fab")
		)
		(fp_line
			(start 0.120396 0.3048)
			(end 0.120396 0.2794)
			(stroke
				(width 0.1)
				(type default)
			)
			(layer "F.Fab")
		)
		(fp_line
			(start 0.67945 0.3048)
			(end 0.120396 0.3048)
			(stroke
				(width 0.1)
				(type default)
			)
			(layer "F.Fab")
		)
		(fp_line
			(start -0.12065 0.2794)
			(end -0.12065 0.3048)
			(stroke
				(width 0.1)
				(type default)
			)
			(layer "F.Fab")
		)
		(fp_line
			(start 0.120396 0.2794)
			(end -0.12065 0.2794)
			(stroke
				(width 0.1)
				(type default)
			)
			(layer "F.Fab")
		)
		(fp_line
			(start -0.12065 -0.2794)
			(end 0.12065 -0.2794)
			(stroke
				(width 0.1)
				(type default)
			)
			(layer "F.Fab")
		)
		(fp_line
			(start 0.12065 -0.2794)
			(end 0.12065 -0.3048)
			(stroke
				(width 0.1)
				(type default)
			)
			(layer "F.Fab")
		)
		(fp_line
			(start 0.12065 -0.3048)
			(end 0.67945 -0.3048)
			(stroke
				(width 0.1)
				(type default)
			)
			(layer "F.Fab")
		)
		(fp_line
			(start 0.67945 -0.3048)
			(end 0.67945 0.3048)
			(stroke
				(width 0.1)
				(type default)
			)
			(layer "F.Fab")
		)
		(fp_line
			(start -0.67945 -0.305054)
			(end -0.12065 -0.305054)
			(stroke
				(width 0.1)
				(type default)
			)
			(layer "F.Fab")
		)
		(fp_line
			(start -0.12065 -0.305054)
			(end -0.12065 -0.2794)
			(stroke
				(width 0.1)
				(type default)
			)
			(layer "F.Fab")
		)
		(pad "1" smd circle
			(at -0.40005 0 270)
			(size 0 0)
			(layers "F.Cu" "F.Mask" "F.Paste")
			(net "M_BMC_DDR4_MA<10>")
		)
		(pad "2" smd circle
			(at 0.40005 0 270)
			(size 0 0)
			(layers "F.Cu" "F.Mask" "F.Paste")
			(net "P1V2_AUX")
		)
	)
	(footprint ""
		(layer "F.Cu")
		(at 11.3538 -109.347 90)
		(property "Reference" "R838"
			(at 0 0 90)
			(layer "F.SilkS")
			(hide yes)
			(effects
				(font
					(size 1.27 1.27)
				)
			)
		)
		(property "Value" ""
			(at 0 0 90)
			(layer "F.Fab")
			(effects
				(font
					(size 1.27 1.27)
				)
			)
		)
		(duplicate_pad_numbers_are_jumpers no)
		(fp_line
			(start 0.7874 -0.4064)
			(end 0.7874 0.4064)
			(stroke
				(width 0.1524)
				(type default)
			)
			(layer "F.SilkS")
		)
		(fp_line
			(start -0.7874 -0.4064)
			(end 0.7874 -0.4064)
			(stroke
				(width 0.1524)
				(type default)
			)
			(layer "F.SilkS")
		)
		(fp_line
			(start 0.7874 0.4064)
			(end -0.7874 0.4064)
			(stroke
				(width 0.1524)
				(type default)
			)
			(layer "F.SilkS")
		)
		(fp_line
			(start -0.7874 0.4064)
			(end -0.7874 -0.4064)
			(stroke
				(width 0.1524)
				(type default)
			)
			(layer "F.SilkS")
		)
		(fp_line
			(start -0.12065 -0.305054)
			(end -0.12065 -0.2794)
			(stroke
				(width 0.1)
				(type default)
			)
			(layer "F.Fab")
		)
		(fp_line
			(start -0.67945 -0.305054)
			(end -0.12065 -0.305054)
			(stroke
				(width 0.1)
				(type default)
			)
			(layer "F.Fab")
		)
		(fp_line
			(start 0.67945 -0.3048)
			(end 0.67945 0.3048)
			(stroke
				(width 0.1)
				(type default)
			)
			(layer "F.Fab")
		)
		(fp_line
			(start 0.12065 -0.3048)
			(end 0.67945 -0.3048)
			(stroke
				(width 0.1)
				(type default)
			)
			(layer "F.Fab")
		)
		(fp_line
			(start 0.12065 -0.2794)
			(end 0.12065 -0.3048)
			(stroke
				(width 0.1)
				(type default)
			)
			(layer "F.Fab")
		)
		(fp_line
			(start -0.12065 -0.2794)
			(end 0.12065 -0.2794)
			(stroke
				(width 0.1)
				(type default)
			)
			(layer "F.Fab")
		)
		(fp_line
			(start 0.120396 0.2794)
			(end -0.12065 0.2794)
			(stroke
				(width 0.1)
				(type default)
			)
			(layer "F.Fab")
		)
		(fp_line
			(start -0.12065 0.2794)
			(end -0.12065 0.3048)
			(stroke
				(width 0.1)
				(type default)
			)
			(layer "F.Fab")
		)
		(fp_line
			(start 0.67945 0.3048)
			(end 0.120396 0.3048)
			(stroke
				(width 0.1)
				(type default)
			)
			(layer "F.Fab")
		)
		(fp_line
			(start 0.120396 0.3048)
			(end 0.120396 0.2794)
			(stroke
				(width 0.1)
				(type default)
			)
			(layer "F.Fab")
		)
		(fp_line
			(start -0.12065 0.3048)
			(end -0.67945 0.3048)
			(stroke
				(width 0.1)
				(type default)
			)
			(layer "F.Fab")
		)
		(fp_line
			(start -0.67945 0.3048)
			(end -0.67945 -0.305054)
			(stroke
				(width 0.1)
				(type default)
			)
			(layer "F.Fab")
		)
		(pad "1" smd circle
			(at -0.40005 0 90)
			(size 0 0)
			(layers "F.Cu" "F.Mask" "F.Paste")
			(net "HDD_LED_N")
		)
		(pad "2" smd circle
			(at 0.40005 0 90)
			(size 0 0)
			(layers "F.Cu" "F.Mask" "F.Paste")
			(net "FM_HDD_LED_N")
		)
	)
	(footprint ""
		(layer "F.Cu")
		(at 74.09815 -91.061032 180)
		(property "Reference" "C143"
			(at 0 0 180)
			(layer "F.SilkS")
			(hide yes)
			(effects
				(font
					(size 1.27 1.27)
				)
			)
		)
		(property "Value" ""
			(at 0 0 180)
			(layer "F.Fab")
			(effects
				(font
					(size 1.27 1.27)
				)
			)
		)
		(duplicate_pad_numbers_are_jumpers no)
		(fp_line
			(start 0.7874 0.4064)
			(end -0.7874 0.4064)
			(stroke
				(width 0.1524)
				(type default)
			)
			(layer "F.SilkS")
		)
		(fp_line
			(start 0.7874 -0.4064)
			(end 0.7874 0.4064)
			(stroke
				(width 0.1524)
				(type default)
			)
			(layer "F.SilkS")
		)
		(fp_line
			(start -0.7874 0.4064)
			(end -0.7874 -0.4064)
			(stroke
				(width 0.1524)
				(type default)
			)
			(layer "F.SilkS")
		)
		(fp_line
			(start -0.7874 -0.4064)
			(end 0.7874 -0.4064)
			(stroke
				(width 0.1524)
				(type default)
			)
			(layer "F.SilkS")
		)
		(fp_line
			(start 0.67945 0.3048)
			(end 0.120396 0.3048)
			(stroke
				(width 0.1)
				(type default)
			)
			(layer "F.Fab")
		)
		(fp_line
			(start 0.67945 -0.3048)
			(end 0.67945 0.3048)
			(stroke
				(width 0.1)
				(type default)
			)
			(layer "F.Fab")
		)
		(fp_line
			(start 0.12065 -0.2794)
			(end 0.12065 -0.3048)
			(stroke
				(width 0.1)
				(type default)
			)
			(layer "F.Fab")
		)
		(fp_line
			(start 0.12065 -0.3048)
			(end 0.67945 -0.3048)
			(stroke
				(width 0.1)
				(type default)
			)
			(layer "F.Fab")
		)
		(fp_line
			(start 0.120396 0.3048)
			(end 0.120396 0.2794)
			(stroke
				(width 0.1)
				(type default)
			)
			(layer "F.Fab")
		)
		(fp_line
			(start 0.120396 0.2794)
			(end -0.12065 0.2794)
			(stroke
				(width 0.1)
				(type default)
			)
			(layer "F.Fab")
		)
		(fp_line
			(start -0.12065 0.3048)
			(end -0.67945 0.3048)
			(stroke
				(width 0.1)
				(type default)
			)
			(layer "F.Fab")
		)
		(fp_line
			(start -0.12065 0.2794)
			(end -0.12065 0.3048)
			(stroke
				(width 0.1)
				(type default)
			)
			(layer "F.Fab")
		)
		(fp_line
			(start -0.12065 -0.2794)
			(end 0.12065 -0.2794)
			(stroke
				(width 0.1)
				(type default)
			)
			(layer "F.Fab")
		)
		(fp_line
			(start -0.12065 -0.305054)
			(end -0.12065 -0.2794)
			(stroke
				(width 0.1)
				(type default)
			)
			(layer "F.Fab")
		)
		(fp_line
			(start -0.67945 0.3048)
			(end -0.67945 -0.305054)
			(stroke
				(width 0.1)
				(type default)
			)
			(layer "F.Fab")
		)
		(fp_line
			(start -0.67945 -0.305054)
			(end -0.12065 -0.305054)
			(stroke
				(width 0.1)
				(type default)
			)
			(layer "F.Fab")
		)
		(pad "1" smd circle
			(at -0.40005 0 180)
			(size 0 0)
			(layers "F.Cu" "F.Mask" "F.Paste")
			(net "P3V3_AUX")
		)
		(pad "2" smd circle
			(at 0.40005 0 180)
			(size 0 0)
			(layers "F.Cu" "F.Mask" "F.Paste")
			(net "GND")
		)
	)
	(footprint ""
		(layer "F.Cu")
		(at 36.56203 -88.937592 -90)
		(property "Reference" "C244"
			(at 0 0 270)
			(layer "F.SilkS")
			(hide yes)
			(effects
				(font
					(size 1.27 1.27)
				)
			)
		)
		(property "Value" ""
			(at 0 0 270)
			(layer "F.Fab")
			(effects
				(font
					(size 1.27 1.27)
				)
			)
		)
		(duplicate_pad_numbers_are_jumpers no)
		(fp_line
			(start -0.7874 0.4064)
			(end -0.7874 -0.4064)
			(stroke
				(width 0.1524)
				(type default)
			)
			(layer "F.SilkS")
		)
		(fp_line
			(start 0.7874 0.4064)
			(end -0.7874 0.4064)
			(stroke
				(width 0.1524)
				(type default)
			)
			(layer "F.SilkS")
		)
		(fp_line
			(start -0.7874 -0.4064)
			(end 0.7874 -0.4064)
			(stroke
				(width 0.1524)
				(type default)
			)
			(layer "F.SilkS")
		)
		(fp_line
			(start 0.7874 -0.4064)
			(end 0.7874 0.4064)
			(stroke
				(width 0.1524)
				(type default)
			)
			(layer "F.SilkS")
		)
		(fp_line
			(start -0.67945 0.3048)
			(end -0.67945 -0.305054)
			(stroke
				(width 0.1)
				(type default)
			)
			(layer "F.Fab")
		)
		(fp_line
			(start -0.12065 0.3048)
			(end -0.67945 0.3048)
			(stroke
				(width 0.1)
				(type default)
			)
			(layer "F.Fab")
		)
		(fp_line
			(start 0.120396 0.3048)
			(end 0.120396 0.2794)
			(stroke
				(width 0.1)
				(type default)
			)
			(layer "F.Fab")
		)
		(fp_line
			(start 0.67945 0.3048)
			(end 0.120396 0.3048)
			(stroke
				(width 0.1)
				(type default)
			)
			(layer "F.Fab")
		)
		(fp_line
			(start -0.12065 0.2794)
			(end -0.12065 0.3048)
			(stroke
				(width 0.1)
				(type default)
			)
			(layer "F.Fab")
		)
		(fp_line
			(start 0.120396 0.2794)
			(end -0.12065 0.2794)
			(stroke
				(width 0.1)
				(type default)
			)
			(layer "F.Fab")
		)
		(fp_line
			(start -0.12065 -0.2794)
			(end 0.12065 -0.2794)
			(stroke
				(width 0.1)
				(type default)
			)
			(layer "F.Fab")
		)
		(fp_line
			(start 0.12065 -0.2794)
			(end 0.12065 -0.3048)
			(stroke
				(width 0.1)
				(type default)
			)
			(layer "F.Fab")
		)
		(fp_line
			(start 0.12065 -0.3048)
			(end 0.67945 -0.3048)
			(stroke
				(width 0.1)
				(type default)
			)
			(layer "F.Fab")
		)
		(fp_line
			(start 0.67945 -0.3048)
			(end 0.67945 0.3048)
			(stroke
				(width 0.1)
				(type default)
			)
			(layer "F.Fab")
		)
		(fp_line
			(start -0.67945 -0.305054)
			(end -0.12065 -0.305054)
			(stroke
				(width 0.1)
				(type default)
			)
			(layer "F.Fab")
		)
		(fp_line
			(start -0.12065 -0.305054)
			(end -0.12065 -0.2794)
			(stroke
				(width 0.1)
				(type default)
			)
			(layer "F.Fab")
		)
		(pad "1" smd circle
			(at -0.40005 0 270)
			(size 0 0)
			(layers "F.Cu" "F.Mask" "F.Paste")
			(net "P3V3_AUX")
		)
		(pad "2" smd circle
			(at 0.40005 0 270)
			(size 0 0)
			(layers "F.Cu" "F.Mask" "F.Paste")
			(net "GND")
		)
	)
	(footprint ""
		(layer "F.Cu")
		(at 80.280764 -28.54579 90)
		(property "Reference" "R604"
			(at 0 0 90)
			(layer "F.SilkS")
			(hide yes)
			(effects
				(font
					(size 1.27 1.27)
				)
			)
		)
		(property "Value" ""
			(at 0 0 90)
			(layer "F.Fab")
			(effects
				(font
					(size 1.27 1.27)
				)
			)
		)
		(duplicate_pad_numbers_are_jumpers no)
		(fp_line
			(start 0.7874 -0.4064)
			(end 0.7874 0.4064)
			(stroke
				(width 0.1524)
				(type default)
			)
			(layer "F.SilkS")
		)
		(fp_line
			(start -0.7874 -0.4064)
			(end 0.7874 -0.4064)
			(stroke
				(width 0.1524)
				(type default)
			)
			(layer "F.SilkS")
		)
		(fp_line
			(start 0.7874 0.4064)
			(end -0.7874 0.4064)
			(stroke
				(width 0.1524)
				(type default)
			)
			(layer "F.SilkS")
		)
		(fp_line
			(start -0.7874 0.4064)
			(end -0.7874 -0.4064)
			(stroke
				(width 0.1524)
				(type default)
			)
			(layer "F.SilkS")
		)
		(fp_line
			(start -0.12065 -0.305054)
			(end -0.12065 -0.2794)
			(stroke
				(width 0.1)
				(type default)
			)
			(layer "F.Fab")
		)
		(fp_line
			(start -0.67945 -0.305054)
			(end -0.12065 -0.305054)
			(stroke
				(width 0.1)
				(type default)
			)
			(layer "F.Fab")
		)
		(fp_line
			(start 0.67945 -0.3048)
			(end 0.67945 0.3048)
			(stroke
				(width 0.1)
				(type default)
			)
			(layer "F.Fab")
		)
		(fp_line
			(start 0.12065 -0.3048)
			(end 0.67945 -0.3048)
			(stroke
				(width 0.1)
				(type default)
			)
			(layer "F.Fab")
		)
		(fp_line
			(start 0.12065 -0.2794)
			(end 0.12065 -0.3048)
			(stroke
				(width 0.1)
				(type default)
			)
			(layer "F.Fab")
		)
		(fp_line
			(start -0.12065 -0.2794)
			(end 0.12065 -0.2794)
			(stroke
				(width 0.1)
				(type default)
			)
			(layer "F.Fab")
		)
		(fp_line
			(start 0.120396 0.2794)
			(end -0.12065 0.2794)
			(stroke
				(width 0.1)
				(type default)
			)
			(layer "F.Fab")
		)
		(fp_line
			(start -0.12065 0.2794)
			(end -0.12065 0.3048)
			(stroke
				(width 0.1)
				(type default)
			)
			(layer "F.Fab")
		)
		(fp_line
			(start 0.67945 0.3048)
			(end 0.120396 0.3048)
			(stroke
				(width 0.1)
				(type default)
			)
			(layer "F.Fab")
		)
		(fp_line
			(start 0.120396 0.3048)
			(end 0.120396 0.2794)
			(stroke
				(width 0.1)
				(type default)
			)
			(layer "F.Fab")
		)
		(fp_line
			(start -0.12065 0.3048)
			(end -0.67945 0.3048)
			(stroke
				(width 0.1)
				(type default)
			)
			(layer "F.Fab")
		)
		(fp_line
			(start -0.67945 0.3048)
			(end -0.67945 -0.305054)
			(stroke
				(width 0.1)
				(type default)
			)
			(layer "F.Fab")
		)
		(pad "1" smd circle
			(at -0.40005 0 90)
			(size 0 0)
			(layers "F.Cu" "F.Mask" "F.Paste")
			(net "LED_POSTCODE_0")
		)
		(pad "2" smd circle
			(at 0.40005 0 90)
			(size 0 0)
			(layers "F.Cu" "F.Mask" "F.Paste")
			(net "LED_POSTCODE_0_R")
		)
	)
)
